(kicad_pcb
	(version 20260206)
	(generator "pcbnew")
	(generator_version "10.0")
	(general
		(thickness 1.6)
		(legacy_teardrops no)
	)
	(paper "A4")
	(title_block
		(title "01162023_DA0F0TEBIF0_F0T_Expander_BD_F_brd_V02_OCP.brd")
		(comment 1 "Grand Teton / footprints 5716-5721 of 9728")
	)
	(layers
		(0 "F.Cu" signal "TOP")
		(4 "In1.Cu" signal "GND")
		(6 "In2.Cu" signal "VCC")
		(8 "In3.Cu" signal "VCC1")
		(10 "In4.Cu" signal "GND1")
		(12 "In5.Cu" signal "IN1")
		(14 "In6.Cu" signal "GND2")
		(16 "In7.Cu" signal "IN2")
		(18 "In8.Cu" signal "GND3")
		(20 "In9.Cu" signal "IN3")
		(22 "In10.Cu" signal "GND4")
		(24 "In11.Cu" signal "IN4")
		(26 "In12.Cu" signal "GND5")
		(28 "In13.Cu" signal "IN5")
		(30 "In14.Cu" signal "GND6")
		(32 "In15.Cu" signal "IN6")
		(34 "In16.Cu" signal "GND7")
		(2 "B.Cu" signal "BOTTOM")
		(9 "F.Adhes" user "F.Adhesive")
		(11 "B.Adhes" user "B.Adhesive")
		(13 "F.Paste" user "Package Geometry/Pastemask Top")
		(15 "B.Paste" user "Package Geometry/Pastemask Bottom")
		(5 "F.SilkS" user "Ref Des/Silkscreen Top")
		(7 "B.SilkS" user "Ref Des/Silkscreen Bottom")
		(1 "F.Mask" user "Board Geometry/Soldermask Top")
		(3 "B.Mask" user "Board Geometry/Soldermask Bottom")
		(17 "Dwgs.User" user "User.Drawings")
		(19 "Cmts.User" user "User.Comments")
		(21 "Eco1.User" user "User.Eco1")
		(23 "Eco2.User" user "User.Eco2")
		(25 "Edge.Cuts" user "Board Geometry/Outline")
		(27 "Margin" user)
		(31 "F.CrtYd" user "Package Geometry/Place Bound Top")
		(29 "B.CrtYd" user "Package Geometry/Place Bound Bottom")
		(35 "F.Fab" user "Ref Des/Assembly Top")
		(33 "B.Fab" user "Ref Des/Assembly Bottom")
	)
	(footprint ""
		(layer "F.Cu")
		(at 136.97839 -184.656984 -90)
		(property "Reference" "R1109"
			(at 0 0 270)
			(layer "F.SilkS")
			(hide yes)
			(effects
				(font
					(size 1.27 1.27)
				)
			)
		)
		(property "Value" ""
			(at 0 0 270)
			(layer "F.Fab")
			(effects
				(font
					(size 1.27 1.27)
				)
			)
		)
		(duplicate_pad_numbers_are_jumpers no)
		(fp_line
			(start -0.7874 -0.4064)
			(end 0.7874 -0.4064)
			(stroke
				(width 0.1524)
				(type default)
			)
			(layer "F.SilkS")
		)
		(fp_line
			(start -0.67945 0.3048)
			(end -0.67945 -0.305054)
			(stroke
				(width 0.1)
				(type default)
			)
			(layer "F.Fab")
		)
		(fp_line
			(start -0.12065 0.3048)
			(end -0.67945 0.3048)
			(stroke
				(width 0.1)
				(type default)
			)
			(layer "F.Fab")
		)
		(fp_line
			(start 0.120396 0.3048)
			(end 0.120396 0.2794)
			(stroke
				(width 0.1)
				(type default)
			)
			(layer "F.Fab")
		)
		(fp_line
			(start 0.67945 0.3048)
			(end 0.120396 0.3048)
			(stroke
				(width 0.1)
				(type default)
			)
			(layer "F.Fab")
		)
		(fp_line
			(start -0.12065 0.2794)
			(end -0.12065 0.3048)
			(stroke
				(width 0.1)
				(type default)
			)
			(layer "F.Fab")
		)
		(fp_line
			(start 0.120396 0.2794)
			(end -0.12065 0.2794)
			(stroke
				(width 0.1)
				(type default)
			)
			(layer "F.Fab")
		)
		(fp_line
			(start -0.12065 -0.2794)
			(end 0.12065 -0.2794)
			(stroke
				(width 0.1)
				(type default)
			)
			(layer "F.Fab")
		)
		(fp_line
			(start 0.12065 -0.2794)
			(end 0.12065 -0.3048)
			(stroke
				(width 0.1)
				(type default)
			)
			(layer "F.Fab")
		)
		(fp_line
			(start 0.12065 -0.3048)
			(end 0.67945 -0.3048)
			(stroke
				(width 0.1)
				(type default)
			)
			(layer "F.Fab")
		)
		(fp_line
			(start 0.67945 -0.3048)
			(end 0.67945 0.3048)
			(stroke
				(width 0.1)
				(type default)
			)
			(layer "F.Fab")
		)
		(fp_line
			(start -0.67945 -0.305054)
			(end -0.12065 -0.305054)
			(stroke
				(width 0.1)
				(type default)
			)
			(layer "F.Fab")
		)
		(fp_line
			(start -0.12065 -0.305054)
			(end -0.12065 -0.2794)
			(stroke
				(width 0.1)
				(type default)
			)
			(layer "F.Fab")
		)
		(pad "1" smd circle
			(at -0.40005 0 270)
			(size 0 0)
			(layers "F.Cu" "F.Mask" "F.Paste")
			(net "CLK_100M_DB2000QL_NIC7_R_DP")
		)
		(pad "2" smd circle
			(at 0.40005 0 270)
			(size 0 0)
			(layers "F.Cu" "F.Mask" "F.Paste")
			(net "CLK_100M_DB2000QL_NIC7_DP")
		)
	)
	(footprint ""
		(layer "F.Cu")
		(at 5.866892 -52.543456 180)
		(property "Reference" "PC500"
			(at 0 0 180)
			(layer "F.SilkS")
			(hide yes)
			(effects
				(font
					(size 1.27 1.27)
				)
			)
		)
		(property "Value" ""
			(at 0 0 180)
			(layer "F.Fab")
			(effects
				(font
					(size 1.27 1.27)
				)
			)
		)
		(duplicate_pad_numbers_are_jumpers no)
		(fp_line
			(start 0.7874 0.4064)
			(end -0.7874 0.4064)
			(stroke
				(width 0.1524)
				(type default)
			)
			(layer "F.SilkS")
		)
		(fp_line
			(start 0.7874 -0.4064)
			(end 0.7874 0.4064)
			(stroke
				(width 0.1524)
				(type default)
			)
			(layer "F.SilkS")
		)
		(fp_line
			(start -0.7874 0.4064)
			(end -0.7874 -0.4064)
			(stroke
				(width 0.1524)
				(type default)
			)
			(layer "F.SilkS")
		)
		(fp_line
			(start -0.7874 -0.4064)
			(end 0.7874 -0.4064)
			(stroke
				(width 0.1524)
				(type default)
			)
			(layer "F.SilkS")
		)
		(fp_line
			(start 0.67945 0.3048)
			(end 0.120396 0.3048)
			(stroke
				(width 0.1)
				(type default)
			)
			(layer "F.Fab")
		)
		(fp_line
			(start 0.67945 -0.3048)
			(end 0.67945 0.3048)
			(stroke
				(width 0.1)
				(type default)
			)
			(layer "F.Fab")
		)
		(fp_line
			(start 0.12065 -0.2794)
			(end 0.12065 -0.3048)
			(stroke
				(width 0.1)
				(type default)
			)
			(layer "F.Fab")
		)
		(fp_line
			(start 0.12065 -0.3048)
			(end 0.67945 -0.3048)
			(stroke
				(width 0.1)
				(type default)
			)
			(layer "F.Fab")
		)
		(fp_line
			(start 0.120396 0.3048)
			(end 0.120396 0.2794)
			(stroke
				(width 0.1)
				(type default)
			)
			(layer "F.Fab")
		)
		(fp_line
			(start 0.120396 0.2794)
			(end -0.12065 0.2794)
			(stroke
				(width 0.1)
				(type default)
			)
			(layer "F.Fab")
		)
		(fp_line
			(start -0.12065 0.3048)
			(end -0.67945 0.3048)
			(stroke
				(width 0.1)
				(type default)
			)
			(layer "F.Fab")
		)
		(fp_line
			(start -0.12065 0.2794)
			(end -0.12065 0.3048)
			(stroke
				(width 0.1)
				(type default)
			)
			(layer "F.Fab")
		)
		(fp_line
			(start -0.12065 -0.2794)
			(end 0.12065 -0.2794)
			(stroke
				(width 0.1)
				(type default)
			)
			(layer "F.Fab")
		)
		(fp_line
			(start -0.12065 -0.305054)
			(end -0.12065 -0.2794)
			(stroke
				(width 0.1)
				(type default)
			)
			(layer "F.Fab")
		)
		(fp_line
			(start -0.67945 0.3048)
			(end -0.67945 -0.305054)
			(stroke
				(width 0.1)
				(type default)
			)
			(layer "F.Fab")
		)
		(fp_line
			(start -0.67945 -0.305054)
			(end -0.12065 -0.305054)
			(stroke
				(width 0.1)
				(type default)
			)
			(layer "F.Fab")
		)
		(pad "1" smd circle
			(at -0.40005 0 180)
			(size 0 0)
			(layers "F.Cu" "F.Mask" "F.Paste")
			(net "P3V3_SSD0")
		)
		(pad "2" smd circle
			(at 0.40005 0 180)
			(size 0 0)
			(layers "F.Cu" "F.Mask" "F.Paste")
			(net "GND")
		)
	)
	(footprint ""
		(layer "F.Cu")
		(at 238.124746 -111.999268 180)
		(property "Reference" "R949"
			(at 0 0 180)
			(layer "F.SilkS")
			(hide yes)
			(effects
				(font
					(size 1.27 1.27)
				)
			)
		)
		(property "Value" ""
			(at 0 0 180)
			(layer "F.Fab")
			(effects
				(font
					(size 1.27 1.27)
				)
			)
		)
		(duplicate_pad_numbers_are_jumpers no)
		(fp_line
			(start 0.7874 0.4064)
			(end -0.7874 0.4064)
			(stroke
				(width 0.1524)
				(type default)
			)
			(layer "F.SilkS")
		)
		(fp_line
			(start 0.7874 -0.4064)
			(end 0.7874 0.4064)
			(stroke
				(width 0.1524)
				(type default)
			)
			(layer "F.SilkS")
		)
		(fp_line
			(start -0.7874 0.4064)
			(end -0.7874 -0.4064)
			(stroke
				(width 0.1524)
				(type default)
			)
			(layer "F.SilkS")
		)
		(fp_line
			(start -0.7874 -0.4064)
			(end 0.7874 -0.4064)
			(stroke
				(width 0.1524)
				(type default)
			)
			(layer "F.SilkS")
		)
		(fp_line
			(start 0.67945 0.3048)
			(end 0.120396 0.3048)
			(stroke
				(width 0.1)
				(type default)
			)
			(layer "F.Fab")
		)
		(fp_line
			(start 0.67945 -0.3048)
			(end 0.67945 0.3048)
			(stroke
				(width 0.1)
				(type default)
			)
			(layer "F.Fab")
		)
		(fp_line
			(start 0.12065 -0.2794)
			(end 0.12065 -0.3048)
			(stroke
				(width 0.1)
				(type default)
			)
			(layer "F.Fab")
		)
		(fp_line
			(start 0.12065 -0.3048)
			(end 0.67945 -0.3048)
			(stroke
				(width 0.1)
				(type default)
			)
			(layer "F.Fab")
		)
		(fp_line
			(start 0.120396 0.3048)
			(end 0.120396 0.2794)
			(stroke
				(width 0.1)
				(type default)
			)
			(layer "F.Fab")
		)
		(fp_line
			(start 0.120396 0.2794)
			(end -0.12065 0.2794)
			(stroke
				(width 0.1)
				(type default)
			)
			(layer "F.Fab")
		)
		(fp_line
			(start -0.12065 0.3048)
			(end -0.67945 0.3048)
			(stroke
				(width 0.1)
				(type default)
			)
			(layer "F.Fab")
		)
		(fp_line
			(start -0.12065 0.2794)
			(end -0.12065 0.3048)
			(stroke
				(width 0.1)
				(type default)
			)
			(layer "F.Fab")
		)
		(fp_line
			(start -0.12065 -0.2794)
			(end 0.12065 -0.2794)
			(stroke
				(width 0.1)
				(type default)
			)
			(layer "F.Fab")
		)
		(fp_line
			(start -0.12065 -0.305054)
			(end -0.12065 -0.2794)
			(stroke
				(width 0.1)
				(type default)
			)
			(layer "F.Fab")
		)
		(fp_line
			(start -0.67945 0.3048)
			(end -0.67945 -0.305054)
			(stroke
				(width 0.1)
				(type default)
			)
			(layer "F.Fab")
		)
		(fp_line
			(start -0.67945 -0.305054)
			(end -0.12065 -0.305054)
			(stroke
				(width 0.1)
				(type default)
			)
			(layer "F.Fab")
		)
		(pad "1" smd circle
			(at -0.40005 0 180)
			(size 0 0)
			(layers "F.Cu" "F.Mask" "F.Paste")
			(net "HP_NIC3_EN")
		)
		(pad "2" smd circle
			(at 0.40005 0 180)
			(size 0 0)
			(layers "F.Cu" "F.Mask" "F.Paste")
			(net "P12V_NIC3_CO_EN")
		)
	)
	(footprint ""
		(layer "F.Cu")
		(at 451.090792 -254.5969 -90)
		(property "Reference" "C4410"
			(at 0 0 270)
			(layer "F.SilkS")
			(hide yes)
			(effects
				(font
					(size 1.27 1.27)
				)
			)
		)
		(property "Value" ""
			(at 0 0 270)
			(layer "F.Fab")
			(effects
				(font
					(size 1.27 1.27)
				)
			)
		)
		(duplicate_pad_numbers_are_jumpers no)
		(fp_line
			(start -1.2954 0.5842)
			(end -1.2954 -0.5842)
			(stroke
				(width 0.1524)
				(type default)
			)
			(layer "F.SilkS")
		)
		(fp_line
			(start 1.2954 0.5842)
			(end -1.2954 0.5842)
			(stroke
				(width 0.1524)
				(type default)
			)
			(layer "F.SilkS")
		)
		(fp_line
			(start -1.2954 -0.5842)
			(end 1.2954 -0.5842)
			(stroke
				(width 0.1524)
				(type default)
			)
			(layer "F.SilkS")
		)
		(fp_line
			(start 1.2954 -0.5842)
			(end 1.2954 0.5842)
			(stroke
				(width 0.1524)
				(type default)
			)
			(layer "F.SilkS")
		)
		(fp_line
			(start -0.8636 0.4572)
			(end -0.8636 0.4064)
			(stroke
				(width 0.1)
				(type default)
			)
			(layer "F.Fab")
		)
		(fp_line
			(start 0.8636 0.4572)
			(end -0.8636 0.4572)
			(stroke
				(width 0.1)
				(type default)
			)
			(layer "F.Fab")
		)
		(fp_line
			(start -1.1938 0.4064)
			(end -1.1938 -0.4064)
			(stroke
				(width 0.1)
				(type default)
			)
			(layer "F.Fab")
		)
		(fp_line
			(start -0.8636 0.4064)
			(end -1.1938 0.4064)
			(stroke
				(width 0.1)
				(type default)
			)
			(layer "F.Fab")
		)
		(fp_line
			(start 0.8636 0.4064)
			(end 0.8636 0.4572)
			(stroke
				(width 0.1)
				(type default)
			)
			(layer "F.Fab")
		)
		(fp_line
			(start 1.1938 0.4064)
			(end 0.8636 0.4064)
			(stroke
				(width 0.1)
				(type default)
			)
			(layer "F.Fab")
		)
		(fp_line
			(start -1.1938 -0.4064)
			(end -0.8636 -0.4064)
			(stroke
				(width 0.1)
				(type default)
			)
			(layer "F.Fab")
		)
		(fp_line
			(start -0.8636 -0.4064)
			(end -0.8636 -0.4572)
			(stroke
				(width 0.1)
				(type default)
			)
			(layer "F.Fab")
		)
		(fp_line
			(start 0.8636 -0.4064)
			(end 1.1938 -0.4064)
			(stroke
				(width 0.1)
				(type default)
			)
			(layer "F.Fab")
		)
		(fp_line
			(start 1.1938 -0.4064)
			(end 1.1938 0.4064)
			(stroke
				(width 0.1)
				(type default)
			)
			(layer "F.Fab")
		)
		(fp_line
			(start -0.8636 -0.4572)
			(end 0.8636 -0.4572)
			(stroke
				(width 0.1)
				(type default)
			)
			(layer "F.Fab")
		)
		(fp_line
			(start 0.8636 -0.4572)
			(end 0.8636 -0.4064)
			(stroke
				(width 0.1)
				(type default)
			)
			(layer "F.Fab")
		)
		(pad "1" smd rect
			(at -0.7366 0 180)
			(size 0.7112 0.8128)
			(layers "F.Cu" "F.Mask" "F.Paste")
			(net "P1V25_SERDES_VDDPLL_PEX3_C8")
		)
		(pad "2" smd rect
			(at 0.7366 0 180)
			(size 0.7112 0.8128)
			(layers "F.Cu" "F.Mask" "F.Paste")
			(net "GND")
		)
	)
	(footprint ""
		(layer "F.Cu")
		(at 378.183648 -61.487812 180)
		(property "Reference" "R6015"
			(at 0 0 180)
			(layer "F.SilkS")
			(hide yes)
			(effects
				(font
					(size 1.27 1.27)
				)
			)
		)
		(property "Value" ""
			(at 0 0 180)
			(layer "F.Fab")
			(effects
				(font
					(size 1.27 1.27)
				)
			)
		)
		(duplicate_pad_numbers_are_jumpers no)
		(fp_line
			(start 0.7874 0.4064)
			(end -0.7874 0.4064)
			(stroke
				(width 0.1524)
				(type default)
			)
			(layer "F.SilkS")
		)
		(fp_line
			(start 0.7874 -0.4064)
			(end 0.7874 0.4064)
			(stroke
				(width 0.1524)
				(type default)
			)
			(layer "F.SilkS")
		)
		(fp_line
			(start -0.7874 0.4064)
			(end -0.7874 -0.4064)
			(stroke
				(width 0.1524)
				(type default)
			)
			(layer "F.SilkS")
		)
		(fp_line
			(start -0.7874 -0.4064)
			(end 0.7874 -0.4064)
			(stroke
				(width 0.1524)
				(type default)
			)
			(layer "F.SilkS")
		)
		(fp_line
			(start 0.67945 0.3048)
			(end 0.120396 0.3048)
			(stroke
				(width 0.1)
				(type default)
			)
			(layer "F.Fab")
		)
		(fp_line
			(start 0.67945 -0.3048)
			(end 0.67945 0.3048)
			(stroke
				(width 0.1)
				(type default)
			)
			(layer "F.Fab")
		)
		(fp_line
			(start 0.12065 -0.2794)
			(end 0.12065 -0.3048)
			(stroke
				(width 0.1)
				(type default)
			)
			(layer "F.Fab")
		)
		(fp_line
			(start 0.12065 -0.3048)
			(end 0.67945 -0.3048)
			(stroke
				(width 0.1)
				(type default)
			)
			(layer "F.Fab")
		)
		(fp_line
			(start 0.120396 0.3048)
			(end 0.120396 0.2794)
			(stroke
				(width 0.1)
				(type default)
			)
			(layer "F.Fab")
		)
		(fp_line
			(start 0.120396 0.2794)
			(end -0.12065 0.2794)
			(stroke
				(width 0.1)
				(type default)
			)
			(layer "F.Fab")
		)
		(fp_line
			(start -0.12065 0.3048)
			(end -0.67945 0.3048)
			(stroke
				(width 0.1)
				(type default)
			)
			(layer "F.Fab")
		)
		(fp_line
			(start -0.12065 0.2794)
			(end -0.12065 0.3048)
			(stroke
				(width 0.1)
				(type default)
			)
			(layer "F.Fab")
		)
		(fp_line
			(start -0.12065 -0.2794)
			(end 0.12065 -0.2794)
			(stroke
				(width 0.1)
				(type default)
			)
			(layer "F.Fab")
		)
		(fp_line
			(start -0.12065 -0.305054)
			(end -0.12065 -0.2794)
			(stroke
				(width 0.1)
				(type default)
			)
			(layer "F.Fab")
		)
		(fp_line
			(start -0.67945 0.3048)
			(end -0.67945 -0.305054)
			(stroke
				(width 0.1)
				(type default)
			)
			(layer "F.Fab")
		)
		(fp_line
			(start -0.67945 -0.305054)
			(end -0.12065 -0.305054)
			(stroke
				(width 0.1)
				(type default)
			)
			(layer "F.Fab")
		)
		(pad "1" smd circle
			(at -0.40005 0 180)
			(size 0 0)
			(layers "F.Cu" "F.Mask" "F.Paste")
			(net "PWRGD_P12V_SSD13_D")
		)
		(pad "2" smd circle
			(at 0.40005 0 180)
			(size 0 0)
			(layers "F.Cu" "F.Mask" "F.Paste")
			(net "PWRGD_P12V_SSD13_R")
		)
	)
	(footprint ""
		(layer "F.Cu")
		(at 351.08261 -29.875734)
		(property "Reference" "PU131"
			(at -3.011678 -2.076704 90)
			(unlocked yes)
			(layer "F.SilkS")
			(effects
				(font
					(size 0.7874 0.5842)
					(thickness 0.1524)
				)
			)
		)
		(property "Value" ""
			(at 0 0 0)
			(layer "F.Fab")
			(effects
				(font
					(size 1.27 1.27)
				)
			)
		)
		(duplicate_pad_numbers_are_jumpers no)
		(fp_line
			(start -1.239774 -1.495298)
			(end 1.239774 -1.495298)
			(stroke
				(width 0.1524)
				(type default)
			)
			(layer "F.SilkS")
		)
		(fp_line
			(start -1.239774 1.495298)
			(end -1.239774 -1.495298)
			(stroke
				(width 0.1524)
				(type default)
			)
			(layer "F.SilkS")
		)
		(fp_line
			(start 1.239774 -1.495298)
			(end 1.239774 1.495298)
			(stroke
				(width 0.1524)
				(type default)
			)
			(layer "F.SilkS")
		)
		(fp_line
			(start 1.239774 1.495298)
			(end -1.239774 1.495298)
			(stroke
				(width 0.1524)
				(type default)
			)
			(layer "F.SilkS")
		)
		(fp_poly
			(pts
				(xy -1.904238 -1.263904) (xy -2.62255 -0.545338) (xy -1.545082 -0.186182)
			)
			(stroke
				(width 0)
				(type default)
			)
			(fill yes)
			(layer "F.SilkS")
		)
		(fp_line
			(start -0.8001 -1.050036)
			(end 0.8001 -1.050036)
			(stroke
				(width 0.1)
				(type default)
			)
			(layer "F.Fab")
		)
		(fp_line
			(start -0.8001 1.050036)
			(end -0.8001 -1.050036)
			(stroke
				(width 0.1)
				(type default)
			)
			(layer "F.Fab")
		)
		(fp_line
			(start 0.8001 -1.050036)
			(end 0.8001 1.050036)
			(stroke
				(width 0.1)
				(type default)
			)
			(layer "F.Fab")
		)
		(fp_line
			(start 0.8001 1.050036)
			(end -0.8001 1.050036)
			(stroke
				(width 0.1)
				(type default)
			)
			(layer "F.Fab")
		)
		(fp_poly
			(pts
				(xy -2.458974 -0.508) (xy -2.458974 0.508) (xy -1.442974 0)
			)
			(stroke
				(width 0)
				(type default)
			)
			(fill yes)
			(layer "F.Fab")
		)
		(pad "1_2" smd circle
			(at -0.374904 0 90)
			(size 0 0)
			(layers "F.Cu" "F.Mask" "F.Paste")
			(net "P3V3_AUX")
		)
		(pad "3" smd rect
			(at -0.499872 0.999998)
			(size 0.254 0.7112)
			(layers "F.Cu" "F.Mask" "F.Paste")
			(net "GND")
		)
		(pad "4" smd rect
			(at 0 0.999998)
			(size 0.254 0.7112)
			(layers "F.Cu" "F.Mask" "F.Paste")
			(net "P3V3_SSD12_CO_ILIMIT")
		)
		(pad "5" smd rect
			(at 0.499872 0.999998)
			(size 0.254 0.7112)
			(layers "F.Cu" "F.Mask" "F.Paste")
			(net "P3V3_SSD12_CO_MODE")
		)
		(pad "6_7" smd circle
			(at 0.374904 0 270)
			(size 0 0)
			(layers "F.Cu" "F.Mask" "F.Paste")
			(net "P3V3_SSD12")
		)
		(pad "8" smd rect
			(at 0.499872 -0.999998)
			(size 0.254 0.7112)
			(layers "F.Cu" "F.Mask" "F.Paste")
			(net "P3V3_SSD12_CO_GATE")
		)
		(pad "9" smd rect
			(at 0 -0.999998)
			(size 0.254 0.7112)
			(layers "F.Cu" "F.Mask" "F.Paste")
			(net "P3V3_SSD12_CO_EN")
		)
		(pad "10" smd rect
			(at -0.499872 -0.999998)
			(size 0.254 0.7112)
			(layers "F.Cu" "F.Mask" "F.Paste")
			(net "P3V3_SSD12_CO_DV_DT")
		)
	)
)
